# T6G (Grand Teton) — schematic netlist excerpt (pin names and nets, part order shuffled) for the footprints in the layout excerpt that follows; sources: Cadence DE-HDL packaged netlist, KiCad conversion of 04192023_DAF0TMB3IC0_F0TG_MB_C_brd_V02_OCP.brd

R4058  Q_RES  10K 1% CHIP  pkg 0402LF  page 123 : A = P3V3_AUX ; B = PRSNT_SWB_N
R485  Q_RES  0 5% CHIP  pkg 0402LF  page 27 : A = CPU0_XTRIG_L7 ; B = CPU0_XTRIG_R1_L7

(kicad_pcb
	(version 20260206)
	(generator "pcbnew")
	(generator_version "10.0")
	(general
		(thickness 1.6)
		(legacy_teardrops no)
	)
	(paper "A4")
	(title_block
		(title "04192023_DAF0TMB3IC0_F0TG_MB_C_brd_V02_OCP.brd")
		(comment 1 "Grand Teton / footprints 2645-2646 of 8354")
	)
	(layers
		(0 "F.Cu" signal "TOP")
		(4 "In1.Cu" signal "GND")
		(6 "In2.Cu" signal "IN1")
		(8 "In3.Cu" signal "GND1")
		(10 "In4.Cu" signal "IN2")
		(12 "In5.Cu" signal "GND2")
		(14 "In6.Cu" signal "IN3")
		(16 "In7.Cu" signal "GND3")
		(18 "In8.Cu" signal "VCC")
		(20 "In9.Cu" signal "VCC1")
		(22 "In10.Cu" signal "GND4")
		(24 "In11.Cu" signal "IN4")
		(26 "In12.Cu" signal "GND5")
		(28 "In13.Cu" signal "IN5")
		(30 "In14.Cu" signal "GND6")
		(32 "In15.Cu" signal "IN6")
		(34 "In16.Cu" signal "GND7")
		(2 "B.Cu" signal "BOTTOM")
		(9 "F.Adhes" user "F.Adhesive")
		(11 "B.Adhes" user "B.Adhesive")
		(13 "F.Paste" user "Package Geometry/Pastemask Top")
		(15 "B.Paste" user "Package Geometry/Pastemask Bottom")
		(5 "F.SilkS" user "Ref Des/Silkscreen Top")
		(7 "B.SilkS" user "Ref Des/Silkscreen Bottom")
		(1 "F.Mask" user "Board Geometry/Soldermask Top")
		(3 "B.Mask" user "Board Geometry/Soldermask Bottom")
		(17 "Dwgs.User" user "User.Drawings")
		(19 "Cmts.User" user "User.Comments")
		(21 "Eco1.User" user "User.Eco1")
		(23 "Eco2.User" user "User.Eco2")
		(25 "Edge.Cuts" user "Board Geometry/Outline")
		(27 "Margin" user)
		(31 "F.CrtYd" user "Package Geometry/Place Bound Top")
		(29 "B.CrtYd" user "Package Geometry/Place Bound Bottom")
		(35 "F.Fab" user "Ref Des/Assembly Top")
		(33 "B.Fab" user "Ref Des/Assembly Bottom")
	)
	(footprint ""
		(layer "F.Cu")
		(at 97.279968 -425.817284 -90)
		(property "Reference" "R4058"
			(at 0 0 270)
			(layer "F.SilkS")
			(hide yes)
			(effects
				(font
					(size 1.27 1.27)
				)
			)
		)
		(property "Value" ""
			(at 0 0 270)
			(layer "F.Fab")
			(effects
				(font
					(size 1.27 1.27)
				)
			)
		)
		(duplicate_pad_numbers_are_jumpers no)
		(fp_line
			(start -0.7874 0.4064)
			(end -0.7874 -0.4064)
			(stroke
				(width 0.1524)
				(type default)
			)
			(layer "F.SilkS")
		)
		(fp_line
			(start 0.7874 0.4064)
			(end -0.7874 0.4064)
			(stroke
				(width 0.1524)
				(type default)
			)
			(layer "F.SilkS")
		)
		(fp_line
			(start -0.7874 -0.4064)
			(end 0.7874 -0.4064)
			(stroke
				(width 0.1524)
				(type default)
			)
			(layer "F.SilkS")
		)
		(fp_line
			(start 0.7874 -0.4064)
			(end 0.7874 0.4064)
			(stroke
				(width 0.1524)
				(type default)
			)
			(layer "F.SilkS")
		)
		(fp_line
			(start -0.67945 0.3048)
			(end -0.67945 -0.305054)
			(stroke
				(width 0.1)
				(type default)
			)
			(layer "F.Fab")
		)
		(fp_line
			(start -0.12065 0.3048)
			(end -0.67945 0.3048)
			(stroke
				(width 0.1)
				(type default)
			)
			(layer "F.Fab")
		)
		(fp_line
			(start 0.120396 0.3048)
			(end 0.120396 0.2794)
			(stroke
				(width 0.1)
				(type default)
			)
			(layer "F.Fab")
		)
		(fp_line
			(start 0.67945 0.3048)
			(end 0.120396 0.3048)
			(stroke
				(width 0.1)
				(type default)
			)
			(layer "F.Fab")
		)
		(fp_line
			(start -0.12065 0.2794)
			(end -0.12065 0.3048)
			(stroke
				(width 0.1)
				(type default)
			)
			(layer "F.Fab")
		)
		(fp_line
			(start 0.120396 0.2794)
			(end -0.12065 0.2794)
			(stroke
				(width 0.1)
				(type default)
			)
			(layer "F.Fab")
		)
		(fp_line
			(start -0.12065 -0.2794)
			(end 0.12065 -0.2794)
			(stroke
				(width 0.1)
				(type default)
			)
			(layer "F.Fab")
		)
		(fp_line
			(start 0.12065 -0.2794)
			(end 0.12065 -0.3048)
			(stroke
				(width 0.1)
				(type default)
			)
			(layer "F.Fab")
		)
		(fp_line
			(start 0.12065 -0.3048)
			(end 0.67945 -0.3048)
			(stroke
				(width 0.1)
				(type default)
			)
			(layer "F.Fab")
		)
		(fp_line
			(start 0.67945 -0.3048)
			(end 0.67945 0.3048)
			(stroke
				(width 0.1)
				(type default)
			)
			(layer "F.Fab")
		)
		(fp_line
			(start -0.67945 -0.305054)
			(end -0.12065 -0.305054)
			(stroke
				(width 0.1)
				(type default)
			)
			(layer "F.Fab")
		)
		(fp_line
			(start -0.12065 -0.305054)
			(end -0.12065 -0.2794)
			(stroke
				(width 0.1)
				(type default)
			)
			(layer "F.Fab")
		)
		(pad "1" smd circle
			(at -0.40005 0 270)
			(size 0 0)
			(layers "F.Cu" "F.Mask" "F.Paste")
			(net "P3V3_AUX")
		)
		(pad "2" smd circle
			(at 0.40005 0 270)
			(size 0 0)
			(layers "F.Cu" "F.Mask" "F.Paste")
			(net "PRSNT_SWB_N")
		)
	)
	(footprint ""
		(layer "F.Cu")
		(at 350.44761 -63.904876 180)
		(property "Reference" "R485"
			(at 0 0 180)
			(layer "F.SilkS")
			(hide yes)
			(effects
				(font
					(size 1.27 1.27)
				)
			)
		)
		(property "Value" ""
			(at 0 0 180)
			(layer "F.Fab")
			(effects
				(font
					(size 1.27 1.27)
				)
			)
		)
		(duplicate_pad_numbers_are_jumpers no)
		(fp_line
			(start 0.7874 0.4064)
			(end -0.7874 0.4064)
			(stroke
				(width 0.1524)
				(type default)
			)
			(layer "F.SilkS")
		)
		(fp_line
			(start 0.7874 -0.4064)
			(end 0.7874 0.4064)
			(stroke
				(width 0.1524)
				(type default)
			)
			(layer "F.SilkS")
		)
		(fp_line
			(start -0.7874 0.4064)
			(end -0.7874 -0.4064)
			(stroke
				(width 0.1524)
				(type default)
			)
			(layer "F.SilkS")
		)
		(fp_line
			(start -0.7874 -0.4064)
			(end 0.7874 -0.4064)
			(stroke
				(width 0.1524)
				(type default)
			)
			(layer "F.SilkS")
		)
		(fp_line
			(start 0.67945 0.3048)
			(end 0.120396 0.3048)
			(stroke
				(width 0.1)
				(type default)
			)
			(layer "F.Fab")
		)
		(fp_line
			(start 0.67945 -0.3048)
			(end 0.67945 0.3048)
			(stroke
				(width 0.1)
				(type default)
			)
			(layer "F.Fab")
		)
		(fp_line
			(start 0.12065 -0.2794)
			(end 0.12065 -0.3048)
			(stroke
				(width 0.1)
				(type default)
			)
			(layer "F.Fab")
		)
		(fp_line
			(start 0.12065 -0.3048)
			(end 0.67945 -0.3048)
			(stroke
				(width 0.1)
				(type default)
			)
			(layer "F.Fab")
		)
		(fp_line
			(start 0.120396 0.3048)
			(end 0.120396 0.2794)
			(stroke
				(width 0.1)
				(type default)
			)
			(layer "F.Fab")
		)
		(fp_line
			(start 0.120396 0.2794)
			(end -0.12065 0.2794)
			(stroke
				(width 0.1)
				(type default)
			)
			(layer "F.Fab")
		)
		(fp_line
			(start -0.12065 0.3048)
			(end -0.67945 0.3048)
			(stroke
				(width 0.1)
				(type default)
			)
			(layer "F.Fab")
		)
		(fp_line
			(start -0.12065 0.2794)
			(end -0.12065 0.3048)
			(stroke
				(width 0.1)
				(type default)
			)
			(layer "F.Fab")
		)
		(fp_line
			(start -0.12065 -0.2794)
			(end 0.12065 -0.2794)
			(stroke
				(width 0.1)
				(type default)
			)
			(layer "F.Fab")
		)
		(fp_line
			(start -0.12065 -0.305054)
			(end -0.12065 -0.2794)
			(stroke
				(width 0.1)
				(type default)
			)
			(layer "F.Fab")
		)
		(fp_line
			(start -0.67945 0.3048)
			(end -0.67945 -0.305054)
			(stroke
				(width 0.1)
				(type default)
			)
			(layer "F.Fab")
		)
		(fp_line
			(start -0.67945 -0.305054)
			(end -0.12065 -0.305054)
			(stroke
				(width 0.1)
				(type default)
			)
			(layer "F.Fab")
		)
		(pad "1" smd circle
			(at -0.40005 0 180)
			(size 0 0)
			(layers "F.Cu" "F.Mask" "F.Paste")
			(net "CPU0_XTRIG_L7")
		)
		(pad "2" smd circle
			(at 0.40005 0 180)
			(size 0 0)
			(layers "F.Cu" "F.Mask" "F.Paste")
			(net "CPU0_XTRIG_R1_L7")
		)
	)
)
